# T6G (Grand Teton) — schematic netlist excerpt (pin names and nets, part order shuffled) for the footprints in the layout excerpt that follows; sources: Cadence DE-HDL packaged netlist, KiCad conversion of 04192023_DAF0TMB3IC0_F0TG_MB_C_brd_V02_OCP.brd

R323  Q_RES  0 5% EMPTY  pkg 0402LF  page 161 : A = SMB_CPU0_CPU1_APML_SDA_R2 ; B = SMB_CPU0_CPU1_APML_MUX1_SDA
R446  Q_RES  4.7K 5% CHIP  pkg 0402LF  page 28 : A = IRQ_SMI_ACTIVE_N ; B = PVDD18_S5_P0

(kicad_pcb
	(version 20260206)
	(generator "pcbnew")
	(generator_version "10.0")
	(general
		(thickness 1.6)
		(legacy_teardrops no)
	)
	(paper "A4")
	(title_block
		(title "04192023_DAF0TMB3IC0_F0TG_MB_C_brd_V02_OCP.brd")
		(comment 1 "Grand Teton / footprints 7303-7304 of 8354")
	)
	(layers
		(0 "F.Cu" signal "TOP")
		(4 "In1.Cu" signal "GND")
		(6 "In2.Cu" signal "IN1")
		(8 "In3.Cu" signal "GND1")
		(10 "In4.Cu" signal "IN2")
		(12 "In5.Cu" signal "GND2")
		(14 "In6.Cu" signal "IN3")
		(16 "In7.Cu" signal "GND3")
		(18 "In8.Cu" signal "VCC")
		(20 "In9.Cu" signal "VCC1")
		(22 "In10.Cu" signal "GND4")
		(24 "In11.Cu" signal "IN4")
		(26 "In12.Cu" signal "GND5")
		(28 "In13.Cu" signal "IN5")
		(30 "In14.Cu" signal "GND6")
		(32 "In15.Cu" signal "IN6")
		(34 "In16.Cu" signal "GND7")
		(2 "B.Cu" signal "BOTTOM")
		(9 "F.Adhes" user "F.Adhesive")
		(11 "B.Adhes" user "B.Adhesive")
		(13 "F.Paste" user "Package Geometry/Pastemask Top")
		(15 "B.Paste" user "Package Geometry/Pastemask Bottom")
		(5 "F.SilkS" user "Ref Des/Silkscreen Top")
		(7 "B.SilkS" user "Ref Des/Silkscreen Bottom")
		(1 "F.Mask" user "Board Geometry/Soldermask Top")
		(3 "B.Mask" user "Board Geometry/Soldermask Bottom")
		(17 "Dwgs.User" user "User.Drawings")
		(19 "Cmts.User" user "User.Comments")
		(21 "Eco1.User" user "User.Eco1")
		(23 "Eco2.User" user "User.Eco2")
		(25 "Edge.Cuts" user "Board Geometry/Outline")
		(27 "Margin" user)
		(31 "F.CrtYd" user "Package Geometry/Place Bound Top")
		(29 "B.CrtYd" user "Package Geometry/Place Bound Bottom")
		(35 "F.Fab" user "Ref Des/Assembly Top")
		(33 "B.Fab" user "Ref Des/Assembly Bottom")
	)
	(footprint ""
		(layer "B.Cu")
		(at 230.505 -242.443 90)
		(property "Reference" "R323"
			(at 0 0 90)
			(layer "B.SilkS")
			(hide yes)
			(effects
				(font
					(size 1.27 1.27)
				)
				(justify mirror)
			)
		)
		(property "Value" ""
			(at 0 0 90)
			(layer "B.Fab")
			(effects
				(font
					(size 1.27 1.27)
				)
				(justify mirror)
			)
		)
		(duplicate_pad_numbers_are_jumpers no)
		(fp_line
			(start 0.7874 -0.4064)
			(end -0.7874 -0.4064)
			(stroke
				(width 0.1524)
				(type default)
			)
			(layer "B.SilkS")
		)
		(fp_line
			(start -0.7874 -0.4064)
			(end -0.7874 0.4064)
			(stroke
				(width 0.1524)
				(type default)
			)
			(layer "B.SilkS")
		)
		(fp_line
			(start 0.7874 0.4064)
			(end 0.7874 -0.4064)
			(stroke
				(width 0.1524)
				(type default)
			)
			(layer "B.SilkS")
		)
		(fp_line
			(start -0.7874 0.4064)
			(end 0.7874 0.4064)
			(stroke
				(width 0.1524)
				(type default)
			)
			(layer "B.SilkS")
		)
		(fp_line
			(start 0.67945 -0.305054)
			(end 0.12065 -0.305054)
			(stroke
				(width 0.1)
				(type default)
			)
			(layer "B.Fab")
		)
		(fp_line
			(start 0.12065 -0.305054)
			(end 0.12065 -0.2794)
			(stroke
				(width 0.1)
				(type default)
			)
			(layer "B.Fab")
		)
		(fp_line
			(start -0.12065 -0.3048)
			(end -0.67945 -0.3048)
			(stroke
				(width 0.1)
				(type default)
			)
			(layer "B.Fab")
		)
		(fp_line
			(start -0.67945 -0.3048)
			(end -0.67945 0.3048)
			(stroke
				(width 0.1)
				(type default)
			)
			(layer "B.Fab")
		)
		(fp_line
			(start 0.12065 -0.2794)
			(end -0.12065 -0.2794)
			(stroke
				(width 0.1)
				(type default)
			)
			(layer "B.Fab")
		)
		(fp_line
			(start -0.12065 -0.2794)
			(end -0.12065 -0.3048)
			(stroke
				(width 0.1)
				(type default)
			)
			(layer "B.Fab")
		)
		(fp_line
			(start 0.12065 0.2794)
			(end 0.12065 0.3048)
			(stroke
				(width 0.1)
				(type default)
			)
			(layer "B.Fab")
		)
		(fp_line
			(start -0.120396 0.2794)
			(end 0.12065 0.2794)
			(stroke
				(width 0.1)
				(type default)
			)
			(layer "B.Fab")
		)
		(fp_line
			(start 0.67945 0.3048)
			(end 0.67945 -0.305054)
			(stroke
				(width 0.1)
				(type default)
			)
			(layer "B.Fab")
		)
		(fp_line
			(start 0.12065 0.3048)
			(end 0.67945 0.3048)
			(stroke
				(width 0.1)
				(type default)
			)
			(layer "B.Fab")
		)
		(fp_line
			(start -0.120396 0.3048)
			(end -0.120396 0.2794)
			(stroke
				(width 0.1)
				(type default)
			)
			(layer "B.Fab")
		)
		(fp_line
			(start -0.67945 0.3048)
			(end -0.120396 0.3048)
			(stroke
				(width 0.1)
				(type default)
			)
			(layer "B.Fab")
		)
		(pad "1" smd rect
			(at 0.40005 0 90)
			(size 0.4572 0.508)
			(layers "B.Cu" "B.Mask" "B.Paste")
			(net "SMB_CPU0_CPU1_APML_SDA_R2")
		)
		(pad "2" smd rect
			(at -0.40005 0 90)
			(size 0.4572 0.508)
			(layers "B.Cu" "B.Mask" "B.Paste")
			(net "SMB_CPU0_CPU1_APML_MUX1_SDA")
		)
	)
	(footprint ""
		(layer "B.Cu")
		(at 402.322538 -321.179952 180)
		(property "Reference" "R446"
			(at 0 0 0)
			(layer "B.SilkS")
			(hide yes)
			(effects
				(font
					(size 1.27 1.27)
				)
				(justify mirror)
			)
		)
		(property "Value" ""
			(at 0 0 0)
			(layer "B.Fab")
			(effects
				(font
					(size 1.27 1.27)
				)
				(justify mirror)
			)
		)
		(duplicate_pad_numbers_are_jumpers no)
		(fp_line
			(start 0.7874 0.4064)
			(end 0.7874 -0.4064)
			(stroke
				(width 0.1524)
				(type default)
			)
			(layer "B.SilkS")
		)
		(fp_line
			(start 0.7874 -0.4064)
			(end -0.7874 -0.4064)
			(stroke
				(width 0.1524)
				(type default)
			)
			(layer "B.SilkS")
		)
		(fp_line
			(start -0.7874 0.4064)
			(end 0.7874 0.4064)
			(stroke
				(width 0.1524)
				(type default)
			)
			(layer "B.SilkS")
		)
		(fp_line
			(start -0.7874 -0.4064)
			(end -0.7874 0.4064)
			(stroke
				(width 0.1524)
				(type default)
			)
			(layer "B.SilkS")
		)
		(fp_line
			(start 0.67945 0.3048)
			(end 0.67945 -0.305054)
			(stroke
				(width 0.1)
				(type default)
			)
			(layer "B.Fab")
		)
		(fp_line
			(start 0.67945 -0.305054)
			(end 0.12065 -0.305054)
			(stroke
				(width 0.1)
				(type default)
			)
			(layer "B.Fab")
		)
		(fp_line
			(start 0.12065 0.3048)
			(end 0.67945 0.3048)
			(stroke
				(width 0.1)
				(type default)
			)
			(layer "B.Fab")
		)
		(fp_line
			(start 0.12065 0.2794)
			(end 0.12065 0.3048)
			(stroke
				(width 0.1)
				(type default)
			)
			(layer "B.Fab")
		)
		(fp_line
			(start 0.12065 -0.2794)
			(end -0.12065 -0.2794)
			(stroke
				(width 0.1)
				(type default)
			)
			(layer "B.Fab")
		)
		(fp_line
			(start 0.12065 -0.305054)
			(end 0.12065 -0.2794)
			(stroke
				(width 0.1)
				(type default)
			)
			(layer "B.Fab")
		)
		(fp_line
			(start -0.120396 0.3048)
			(end -0.120396 0.2794)
			(stroke
				(width 0.1)
				(type default)
			)
			(layer "B.Fab")
		)
		(fp_line
			(start -0.120396 0.2794)
			(end 0.12065 0.2794)
			(stroke
				(width 0.1)
				(type default)
			)
			(layer "B.Fab")
		)
		(fp_line
			(start -0.12065 -0.2794)
			(end -0.12065 -0.3048)
			(stroke
				(width 0.1)
				(type default)
			)
			(layer "B.Fab")
		)
		(fp_line
			(start -0.12065 -0.3048)
			(end -0.67945 -0.3048)
			(stroke
				(width 0.1)
				(type default)
			)
			(layer "B.Fab")
		)
		(fp_line
			(start -0.67945 0.3048)
			(end -0.120396 0.3048)
			(stroke
				(width 0.1)
				(type default)
			)
			(layer "B.Fab")
		)
		(fp_line
			(start -0.67945 -0.3048)
			(end -0.67945 0.3048)
			(stroke
				(width 0.1)
				(type default)
			)
			(layer "B.Fab")
		)
		(pad "1" smd circle
			(at 0.40005 0)
			(size 0 0)
			(layers "B.Cu" "B.Mask" "B.Paste")
			(net "IRQ_SMI_ACTIVE_N")
		)
		(pad "2" smd circle
			(at -0.40005 0)
			(size 0 0)
			(layers "B.Cu" "B.Mask" "B.Paste")
			(net "PVDD18_S5_P0")
		)
	)
)
